;LEADER: 12 
;HEADER: 
;CODE  : ASCII 
;FILE  : R4006-B0001-02_R01-1-10.drl for  ... layers TOP and BOTTOM
;DESIGN: R4006-B0001-02_R01.brd
;T01 Holesize 1. = 8.000000 Tolerance = +0.000000/-8.000000 PLATED MILS Quantity = 1182
;T02 Holesize 2. = 10.000000 Tolerance = +0.000000/-10.000000 PLATED MILS Quantity = 1307
;T03 Holesize 3. = 12.000000 Tolerance = +0.000000/-12.000000 PLATED MILS Quantity = 32
;T04 Holesize 4. = 16.000000 Tolerance = +3.000000/-3.000000 PLATED MILS Quantity = 14
;T05 Holesize 5. = 33.000000 Tolerance = +3.000000/-3.000000 PLATED MILS Quantity = 2
;T06 Holesize 6. = 59.000000 Tolerance = +3.000000/-3.000000 PLATED MILS Quantity = 4
;T07 Holesize 7. = 63.000000 Tolerance = +3.000000/-3.000000 PLATED MILS Quantity = 16
;T08 Holesize 8. = 76.000000 Tolerance = +3.000000/-3.000000 PLATED MILS Quantity = 6
;T09 Holesize 9. = 79.000000 Tolerance = +3.000000/-3.000000 PLATED MILS Quantity = 8
;T10 Holesize 10. = 166.000000 Tolerance = +3.000000/-3.000000 PLATED MILS Quantity = 4
;T12 Holesize 11. = 100.000000 Tolerance = +2.000000/-2.000000 NON_PLATED MILS Quantity = 4
;T13 Holesize 12. = 118.000000 Tolerance = +2.000000/-2.000000 NON_PLATED MILS Quantity = 2
;T14 Holesize 13. = 125.000000 Tolerance = +2.000000/-2.000000 NON_PLATED MILS Quantity = 4
%
G90
T01
X0000012878Y0000021717
X0000016878Y0000021717
X0000020878Y0000021717
X0000024878Y0000021717
X0000004000Y0000049619
X0000004000Y0000045619
X0000004000Y0000041619
X0000004000Y0000037619
X0000004000Y0000033619
X0000004000Y0000029619
X0000004000Y0000025619
X0000004878Y0000021717
X0000008878Y0000021717
X0000028878Y0000021717
X0000032878Y0000021717
X0000036878Y0000021717
X0000004000Y0000285619
X0000004000Y0000281619
X0000004000Y0000313619
X0000004000Y0000309619
X0000004000Y0000305619
X0000004000Y0000301619
X0000004000Y0000349619
X0000004000Y0000345619
X0000004000Y0000341619
X0000004000Y0000337619
X0000004000Y0000297619
X0000004000Y0000293619
X0000004000Y0000289619
X0000008413Y0000433598
X0000004413Y0000433598
X0000004000Y0000429619
X0000004000Y0000425619
X0000004000Y0000421619
X0000004000Y0000417619
X0000004000Y0000413619
X0000004000Y0000409619
X0000004000Y0000405619
X0000004000Y0000401619
X0000004000Y0000397619
X0000004000Y0000393619
X0000004000Y0000389619
X0000004000Y0000385619
X0000004000Y0000381619
X0000004000Y0000377619
X0000004000Y0000373619
X0000004000Y0000369619
X0000004000Y0000365619
X0000004000Y0000361619
X0000004000Y0000357619
X0000004000Y0000353619
X0000036413Y0000433598
X0000032413Y0000433598
X0000028413Y0000433598
X0000024413Y0000433598
X0000020413Y0000433598
X0000016413Y0000433598
X0000012413Y0000433598
X0000107300Y0000382500
X0000070300Y0000357500
X0000073500Y0000357500
X0000110500Y0000382500
X0000075580Y0000419004
X0000070500Y0000419000
X0000085500Y0000420500
X0000090000Y0000420500
X0000098000Y0000420000
X0000138250Y0000372250
X0000138500Y0000387500
X0000104100Y0000382500
X0000113700Y0000382500
X0000067100Y0000357500
X0000076700Y0000357500
X0000044413Y0000433598
X0000040413Y0000433598
X0000064413Y0000433598
X0000060413Y0000433598
X0000056413Y0000433598
X0000052413Y0000433598
X0000048413Y0000433598
X0000080413Y0000433598
X0000076413Y0000433598
X0000072413Y0000433598
X0000068413Y0000433598
X0000100413Y0000433598
X0000096413Y0000433598
X0000092413Y0000433598
X0000088413Y0000433598
X0000084413Y0000433598
X0000136413Y0000433598
X0000132413Y0000433598
X0000128413Y0000433598
X0000124413Y0000433598
X0000120413Y0000433598
X0000116413Y0000433598
X0000112413Y0000433598
X0000108413Y0000433598
X0000104413Y0000433598
X0000131500Y0000290500
X0000136000Y0000290500
X0000063800Y0000274000
X0000075500Y0000282500
X0000087100Y0000271300
X0000068600Y0000274000
X0000073600Y0000252500
X0000077964Y0000260100
X0000072000Y0000271400
X0000082500Y0000273200
X0000067000Y0000283100
X0000079248Y0000266100
X0000085800Y0000287452
X0000085600Y0000263700
X0000075800Y0000274300
X0000089600Y0000248900
X0000082500Y0000230500
X0000079500Y0000234500
X0000088300Y0000163900
X0000075950Y0000164200
X0000076100Y0000154400
X0000086800Y0000230000
X0000084600Y0000248900
X0000079600Y0000248900
X0000112880Y0000073020
X0000126000Y0000062000
X0000126000Y0000067000
X0000051765Y0000096600
X0000046000Y0000082000
X0000112800Y0000066600
X0000198135Y0000036500
X0000191535Y0000041200
X0000210500Y0000030500
X0000187598Y0000028900
X0000186000Y0000033000
X0000189500Y0000033000
X0000187598Y0000036900
X0000201950Y0000029050
X0000191535Y0000028900
X0000180341Y0000047225
X0000232700Y0000029100
X0000057859Y0000052313
X0000061463Y0000054048
X0000065460Y0000054197
X0000069460Y0000054197
X0000073460Y0000054197
X0000077460Y0000054197
X0000081460Y0000054197
X0000085460Y0000054197
X0000089460Y0000054197
X0000093460Y0000054197
X0000097460Y0000054197
X0000101460Y0000054197
X0000105460Y0000054197
X0000109460Y0000054197
X0000113460Y0000054197
X0000117460Y0000054197
X0000142163Y0000021717
X0000146163Y0000021717
X0000150163Y0000021717
X0000154163Y0000021717
X0000138500Y0000075000
X0000121460Y0000054197
X0000125460Y0000054197
X0000129450Y0000053917
X0000132920Y0000051926
X0000159112Y0000045654
X0000160736Y0000049309
X0000158795Y0000029667
X0000158795Y0000033667
X0000158795Y0000037667
X0000158795Y0000041667
X0000158163Y0000021717
X0000158795Y0000025667
X0000139500Y0000062500
X0000142000Y0000069535
X0000142070Y0000077900
X0000196497Y0000076502
X0000180910Y0000063390
X0000145900Y0000075200
X0000195000Y0000054550
X0000180390Y0000070720
X0000180620Y0000077890
X0000178196Y0000050601
X0000163543Y0000052159
X0000055055Y0000045073
X0000055558Y0000049041
X0000055055Y0000029073
X0000055055Y0000033073
X0000055055Y0000037073
X0000055055Y0000041073
X0000048878Y0000021717
X0000052878Y0000021717
X0000055055Y0000025073
X0000040878Y0000021717
X0000044878Y0000021717
X0000138163Y0000021717
X0000144000Y0000062500
X0000151840Y0000079935
X0000134977Y0000048496
X0000135299Y0000044509
X0000135299Y0000040509
X0000135299Y0000036509
X0000135299Y0000032509
X0000135299Y0000028509
X0000135299Y0000024509
X0000214810Y0000078810
X0000203000Y0000075000
X0000207880Y0000078740
X0000148500Y0000062500
X0000183170Y0000056390
X0000208500Y0000301700
X0000213500Y0000301700
X0000218500Y0000301700
X0000222000Y0000330000
X0000224500Y0000302000
X0000212800Y0000289500
X0000209660Y0000331500
X0000221800Y0000289500
X0000217300Y0000289500
X0000208300Y0000289500
X0000153150Y0000394590
X0000151100Y0000386300
X0000151530Y0000406300
X0000152100Y0000399300
X0000152200Y0000416300
X0000148500Y0000376000
X0000160600Y0000417400
X0000163300Y0000382900
X0000153500Y0000390500
X0000196413Y0000433598
X0000192413Y0000433598
X0000188413Y0000433598
X0000184413Y0000433598
X0000180413Y0000433598
X0000176413Y0000433598
X0000172413Y0000433598
X0000168413Y0000433598
X0000164413Y0000433598
X0000160413Y0000433598
X0000156413Y0000433598
X0000167100Y0000405600
X0000152413Y0000433598
X0000148413Y0000433598
X0000144413Y0000433598
X0000140413Y0000433598
X0000236413Y0000433598
X0000232413Y0000433598
X0000228413Y0000433598
X0000224413Y0000433598
X0000220413Y0000433598
X0000216413Y0000433598
X0000212413Y0000433598
X0000208413Y0000433598
X0000204413Y0000433598
X0000200413Y0000433598
X0000276413Y0000433598
X0000272413Y0000433598
X0000268413Y0000433598
X0000264413Y0000433598
X0000260413Y0000433598
X0000256413Y0000433598
X0000252413Y0000433598
X0000248413Y0000433598
X0000244413Y0000433598
X0000240413Y0000433598
X0000280413Y0000433598
X0000284413Y0000433598
X0000288413Y0000433598
X0000292413Y0000433598
X0000296413Y0000433598
X0000300413Y0000433598
X0000304413Y0000433598
X0000308413Y0000433598
X0000312413Y0000433598
X0000316413Y0000433598
X0000320413Y0000433598
X0000324413Y0000433598
X0000328413Y0000433598
X0000332413Y0000433598
X0000336413Y0000433598
X0000336525Y0000330500
X0000336500Y0000295000
X0000293200Y0000329500
X0000289600Y0000330100
X0000324300Y0000254700
X0000318000Y0000268500
X0000334350Y0000282000
X0000322200Y0000338500
X0000310600Y0000335000
X0000322200Y0000320500
X0000298700Y0000323500
X0000298700Y0000327000
X0000297700Y0000335100
X0000336525Y0000325500
X0000336525Y0000320500
X0000286151Y0000329500
X0000310600Y0000330500
X0000322200Y0000325000
X0000327800Y0000246800
X0000324000Y0000236000
X0000328500Y0000238645
X0000322710Y0000190299
X0000325910Y0000190299
X0000284500Y0000190700
X0000284500Y0000181100
X0000319510Y0000190299
X0000329110Y0000190299
X0000286600Y0000198700
X0000277000Y0000198700
X0000280200Y0000198700
X0000283400Y0000198700
X0000284500Y0000187500
X0000284500Y0000184300
X0000327500Y0000232000
X0000332600Y0000246600
X0000240508Y0000073100
X0000240508Y0000069900
X0000337500Y0000119400
X0000337500Y0000116200
X0000307300Y0000061300
X0000263507Y0000076300
X0000278655Y0000076300
X0000273107Y0000076300
X0000253422Y0000076300
X0000243822Y0000076300
X0000240508Y0000066700
X0000240508Y0000076300
X0000337500Y0000122600
X0000337500Y0000113000
X0000338599Y0000108500
X0000333402Y0000054197
X0000337402Y0000054197
X0000317025Y0000082975
X0000317402Y0000054197
X0000321402Y0000054197
X0000325402Y0000054197
X0000329402Y0000054197
X0000310237Y0000089763
X0000288255Y0000076300
X0000263300Y0000052200
X0000312500Y0000087500
X0000314763Y0000085237
X0000281855Y0000076300
X0000285055Y0000076300
X0000266707Y0000076300
X0000269907Y0000076300
X0000247022Y0000076300
X0000250222Y0000076300
X0000406879Y0000143005
X0000414753Y0000146942
X0000418690Y0000146942
X0000410816Y0000139067
X0000414753Y0000139067
X0000410816Y0000143005
X0000414753Y0000143005
X0000418690Y0000143005
X0000422627Y0000143005
X0000422627Y0000139067
X0000426564Y0000139067
X0000426564Y0000131193
X0000434437Y0000131193
X0000434437Y0000135130
X0000434437Y0000139067
X0000426564Y0000143005
X0000426564Y0000146942
X0000438374Y0000139067
X0000438374Y0000143005
X0000391130Y0000135130
X0000395067Y0000135130
X0000399000Y0000131188
X0000399000Y0000135125
X0000406874Y0000131188
X0000410811Y0000131188
X0000402942Y0000139067
X0000406879Y0000139067
X0000418690Y0000131193
X0000422627Y0000131193
X0000410816Y0000135130
X0000414753Y0000135130
X0000418690Y0000135130
X0000422627Y0000135130
X0000438374Y0000146942
X0000434437Y0000146942
X0000438374Y0000135130
X0000362500Y0000092000
X0000365700Y0000092000
X0000438374Y0000131193
X0000434437Y0000143005
X0000418690Y0000139067
X0000406879Y0000135130
X0000395067Y0000131193
X0000381700Y0000092400
X0000437650Y0000116599
X0000404850Y0000116099
X0000401650Y0000116099
X0000354664Y0000104707
X0000351464Y0000104707
X0000344999Y0000108500
X0000341799Y0000108500
X0000395067Y0000143005
X0000391130Y0000146942
X0000380400Y0000081600
X0000254527Y0000033900
X0000252700Y0000044000
X0000408050Y0000116099
X0000409200Y0000100500
X0000413622Y0000075000
X0000413402Y0000054197
X0000409402Y0000054197
X0000405402Y0000054197
X0000401402Y0000054197
X0000295800Y0000028900
X0000288057Y0000028900
X0000295835Y0000032100
X0000280052Y0000028900
X0000280087Y0000032100
X0000264339Y0000041700
X0000272309Y0000028900
X0000264304Y0000028900
X0000264339Y0000032100
X0000244619Y0000028900
X0000254527Y0000028900
X0000357864Y0000104707
X0000359300Y0000092000
X0000365402Y0000054197
X0000361402Y0000054197
X0000357402Y0000054197
X0000353402Y0000054197
X0000349402Y0000054197
X0000348264Y0000104707
X0000348199Y0000108500
X0000345402Y0000054197
X0000341402Y0000054197
X0000298726Y0000049471
X0000298726Y0000043529
X0000307708Y0000028900
X0000295835Y0000041700
X0000280087Y0000041700
X0000398450Y0000116099
X0000390000Y0000100500
X0000396400Y0000100500
X0000397402Y0000054197
X0000393402Y0000054197
X0000389402Y0000054197
X0000385402Y0000054197
X0000373500Y0000094000
X0000368900Y0000092000
X0000380500Y0000077400
X0000373500Y0000078000
X0000379500Y0000072500
X0000381402Y0000054197
X0000377402Y0000054197
X0000373402Y0000054197
X0000369402Y0000054197
X0000426564Y0000135130
X0000422627Y0000146942
X0000414753Y0000131193
X0000410816Y0000146942
X0000406879Y0000146942
X0000402942Y0000146942
X0000402942Y0000143005
X0000399005Y0000143005
X0000399005Y0000139067
X0000395067Y0000139067
X0000387193Y0000146942
X0000387193Y0000139067
X0000391130Y0000139067
X0000387193Y0000135130
X0000434450Y0000116599
X0000437402Y0000054197
X0000433402Y0000054197
X0000429402Y0000054197
X0000425402Y0000054197
X0000421402Y0000054197
X0000417402Y0000054197
X0000349000Y0000082500
X0000295835Y0000038500
X0000295835Y0000035300
X0000280087Y0000038500
X0000280087Y0000035300
X0000264339Y0000038500
X0000264339Y0000035300
X0000295835Y0000048100
X0000295835Y0000044900
X0000399005Y0000146942
X0000395067Y0000146942
X0000391130Y0000143005
X0000387193Y0000143005
X0000243500Y0000048650
X0000418690Y0000209933
X0000406879Y0000158753
X0000406879Y0000190248
X0000406879Y0000213870
X0000422627Y0000205996
X0000395067Y0000205996
X0000422627Y0000202059
X0000426564Y0000209933
X0000426564Y0000205996
X0000402942Y0000202059
X0000426564Y0000202059
X0000434437Y0000209933
X0000406879Y0000209933
X0000406879Y0000205996
X0000395067Y0000209933
X0000399005Y0000209933
X0000438374Y0000186311
X0000438374Y0000182374
X0000410816Y0000194185
X0000402942Y0000198122
X0000410816Y0000202059
X0000399005Y0000194185
X0000402942Y0000194185
X0000414753Y0000202059
X0000402942Y0000186311
X0000426564Y0000150879
X0000418690Y0000194185
X0000418690Y0000213870
X0000418690Y0000150879
X0000422627Y0000150879
X0000434437Y0000198122
X0000422627Y0000198122
X0000426564Y0000194185
X0000410816Y0000198122
X0000414753Y0000198122
X0000438374Y0000198122
X0000410816Y0000190248
X0000410816Y0000182374
X0000414753Y0000182374
X0000434437Y0000213870
X0000410816Y0000209933
X0000414753Y0000209933
X0000406879Y0000202059
X0000399005Y0000205996
X0000402942Y0000205996
X0000395067Y0000202059
X0000395067Y0000198122
X0000399005Y0000198122
X0000402942Y0000182374
X0000395067Y0000190248
X0000395067Y0000186311
X0000406879Y0000194185
X0000406879Y0000186311
X0000406879Y0000182374
X0000387193Y0000209933
X0000391130Y0000209933
X0000434437Y0000202059
X0000434437Y0000217807
X0000438374Y0000217807
X0000414753Y0000186311
X0000418690Y0000186311
X0000418690Y0000190248
X0000414753Y0000190248
X0000434437Y0000182374
X0000426564Y0000182374
X0000422627Y0000182374
X0000422627Y0000186311
X0000342900Y0000246800
X0000345930Y0000217000
X0000434437Y0000194185
X0000352300Y0000175000
X0000434437Y0000150879
X0000383128Y0000178372
X0000387193Y0000186311
X0000414753Y0000205996
X0000422627Y0000194185
X0000418690Y0000198122
X0000426564Y0000190248
X0000418690Y0000205996
X0000434437Y0000190248
X0000426564Y0000186311
X0000399005Y0000202059
X0000434437Y0000186311
X0000402942Y0000190248
X0000385500Y0000196154
X0000391130Y0000186311
X0000406879Y0000178437
X0000418690Y0000182374
X0000438374Y0000213870
X0000426564Y0000198122
X0000422627Y0000209933
X0000414753Y0000194185
X0000410816Y0000205996
X0000406879Y0000217807
X0000395067Y0000213870
X0000414753Y0000150879
X0000434437Y0000178437
X0000422627Y0000178437
X0000422627Y0000166627
X0000414753Y0000178437
X0000402942Y0000178437
X0000438374Y0000170564
X0000426564Y0000170564
X0000414753Y0000166627
X0000418690Y0000170564
X0000438374Y0000154816
X0000434437Y0000158753
X0000426564Y0000154816
X0000422627Y0000158753
X0000414753Y0000158753
X0000418690Y0000162690
X0000418690Y0000154816
X0000399005Y0000166627
X0000406879Y0000154816
X0000406879Y0000162690
X0000402942Y0000158753
X0000399005Y0000150879
X0000438374Y0000190248
X0000406879Y0000166627
X0000402942Y0000166627
X0000406879Y0000150879
X0000402942Y0000150879
X0000438374Y0000178437
X0000391130Y0000170564
X0000395067Y0000158753
X0000391130Y0000154816
X0000391130Y0000162690
X0000410816Y0000170564
X0000438374Y0000202059
X0000438374Y0000205996
X0000438374Y0000209933
X0000426564Y0000178437
X0000358400Y0000182700
X0000345301Y0000189899
X0000345301Y0000193099
X0000365101Y0000185159
X0000345301Y0000186699
X0000426564Y0000217807
X0000438374Y0000158753
X0000438374Y0000150879
X0000438374Y0000162690
X0000434437Y0000154816
X0000434437Y0000166627
X0000434437Y0000162690
X0000426564Y0000158753
X0000426564Y0000162690
X0000426564Y0000166627
X0000422627Y0000154816
X0000422627Y0000162690
X0000418690Y0000158753
X0000414753Y0000154816
X0000410816Y0000154816
X0000410816Y0000150879
X0000387193Y0000217807
X0000391130Y0000205996
X0000395067Y0000194185
X0000410816Y0000186311
X0000399005Y0000182374
X0000418690Y0000178437
X0000410816Y0000178437
X0000399005Y0000178437
X0000387193Y0000178437
X0000395067Y0000178437
X0000391130Y0000178437
X0000422627Y0000170564
X0000414753Y0000170564
X0000406879Y0000170564
X0000402942Y0000170564
X0000387193Y0000170564
X0000418690Y0000166627
X0000410816Y0000166627
X0000395067Y0000166627
X0000387193Y0000162690
X0000414753Y0000162690
X0000410816Y0000162690
X0000402942Y0000162690
X0000410816Y0000158753
X0000399005Y0000158753
X0000387193Y0000154816
X0000402942Y0000154816
X0000395067Y0000150879
X0000438374Y0000194185
X0000434437Y0000205996
X0000422627Y0000190248
X0000418690Y0000202059
X0000414753Y0000213870
X0000406879Y0000198122
X0000402942Y0000209933
X0000434437Y0000170564
X0000438374Y0000166627
X0000345301Y0000196299
X0000365101Y0000194759
X0000365101Y0000188359
X0000365101Y0000191559
X0000399005Y0000190248
X0000399005Y0000186311
X0000395067Y0000182374
X0000391130Y0000182374
X0000399005Y0000162690
X0000395067Y0000162690
X0000391130Y0000166627
X0000387193Y0000166627
X0000399005Y0000170564
X0000395067Y0000170564
X0000391130Y0000158753
X0000387193Y0000158753
X0000399005Y0000154816
X0000395067Y0000154816
X0000391130Y0000150879
X0000387193Y0000150879
X0000383000Y0000346600
X0000358250Y0000340050
X0000341500Y0000333500
X0000439500Y0000341500
X0000344000Y0000295000
X0000355000Y0000328000
X0000354800Y0000285600
X0000379300Y0000305000
X0000391600Y0000304800
X0000383000Y0000333500
X0000341500Y0000328500
X0000383000Y0000328500
X0000341500Y0000338500
X0000355000Y0000332500
X0000439500Y0000337892
X0000354800Y0000289800
X0000354850Y0000276100
X0000431169Y0000401169
X0000431900Y0000392200
X0000375500Y0000350500
X0000393500Y0000391000
X0000388500Y0000391000
X0000398500Y0000391000
X0000393500Y0000400000
X0000388500Y0000400000
X0000398500Y0000400000
X0000398000Y0000418500
X0000403000Y0000418500
X0000393000Y0000418500
X0000416800Y0000424000
X0000422337Y0000424000
X0000414000Y0000419000
X0000410463Y0000383000
X0000405463Y0000383000
X0000415463Y0000383000
X0000361124Y0000349876
X0000432000Y0000396500
X0000421360Y0000359970
X0000340413Y0000433598
X0000344413Y0000433598
X0000348413Y0000433598
X0000352413Y0000433598
X0000356413Y0000433598
X0000360413Y0000433598
X0000364413Y0000433598
X0000368413Y0000433598
X0000372413Y0000433598
X0000376413Y0000433598
X0000380413Y0000433598
X0000384413Y0000433598
X0000388413Y0000433598
X0000392413Y0000433598
X0000396413Y0000433598
X0000400413Y0000433598
X0000404413Y0000433598
X0000408413Y0000433598
X0000412413Y0000433598
X0000416413Y0000433598
X0000420413Y0000433598
X0000424413Y0000433598
X0000428413Y0000433598
X0000432413Y0000433598
X0000436413Y0000433598
X0000470500Y0000395000
X0000444000Y0000406500
X0000444000Y0000411500
X0000443000Y0000386500
X0000532300Y0000425700
X0000440413Y0000433598
X0000444413Y0000433598
X0000448413Y0000433598
X0000452413Y0000433598
X0000456413Y0000433598
X0000460413Y0000433598
X0000464413Y0000433598
X0000468413Y0000433598
X0000472413Y0000433598
X0000476413Y0000433598
X0000480413Y0000433598
X0000484413Y0000433598
X0000488413Y0000433598
X0000492413Y0000433598
X0000496413Y0000433598
X0000500413Y0000433598
X0000504413Y0000433598
X0000508413Y0000433598
X0000512413Y0000433598
X0000516413Y0000433598
X0000520413Y0000433598
X0000524413Y0000433598
X0000528413Y0000433598
X0000532413Y0000433598
X0000536413Y0000433598
X0000444000Y0000416500
X0000443000Y0000396500
X0000443000Y0000401500
X0000503000Y0000354600
X0000493500Y0000359000
X0000488500Y0000359000
X0000470462Y0000369462
X0000442500Y0000336089
X0000528500Y0000299000
X0000441500Y0000297500
X0000500000Y0000278799
X0000522600Y0000276200
X0000522400Y0000270700
X0000500500Y0000271100
X0000540318Y0000270436
X0000446500Y0000289500
X0000539977Y0000275124
X0000537500Y0000296607
X0000450185Y0000205996
X0000450185Y0000150879
X0000465933Y0000198122
X0000450185Y0000190248
X0000473807Y0000209933
X0000450185Y0000186311
X0000469870Y0000205996
X0000461996Y0000194185
X0000461996Y0000198122
X0000461996Y0000190248
X0000458059Y0000198122
X0000454122Y0000202059
X0000469870Y0000150879
X0000454122Y0000198122
X0000465933Y0000150879
X0000461996Y0000154816
X0000458059Y0000154816
X0000469870Y0000194185
X0000450185Y0000202059
X0000446248Y0000202059
X0000442311Y0000198122
X0000446248Y0000194185
X0000446248Y0000198122
X0000458059Y0000217807
X0000473807Y0000190248
X0000454122Y0000213870
X0000450185Y0000213870
X0000450185Y0000209933
X0000461996Y0000217807
X0000454122Y0000154816
X0000461996Y0000150879
X0000454122Y0000150879
X0000446248Y0000150879
X0000469870Y0000186311
X0000446248Y0000205996
X0000465933Y0000182374
X0000442311Y0000205996
X0000473807Y0000178437
X0000473807Y0000170564
X0000473807Y0000217807
X0000473807Y0000213870
X0000458059Y0000209933
X0000454122Y0000209933
X0000458059Y0000186311
X0000465933Y0000205996
X0000458059Y0000205996
X0000454122Y0000190248
X0000458059Y0000202059
X0000461996Y0000213870
X0000469870Y0000170564
X0000469870Y0000166627
X0000442311Y0000194185
X0000442311Y0000190248
X0000450185Y0000194185
X0000469870Y0000182374
X0000473807Y0000182374
X0000469870Y0000190248
X0000465933Y0000202059
X0000461996Y0000205996
X0000461996Y0000209933
X0000461996Y0000166627
X0000469870Y0000209933
X0000458060Y0000170564
X0000469870Y0000213870
X0000461996Y0000178437
X0000465933Y0000178437
X0000461996Y0000170564
X0000465933Y0000170564
X0000442311Y0000150879
X0000465933Y0000158753
X0000458059Y0000162690
X0000454122Y0000194185
X0000475000Y0000163000
X0000458059Y0000182374
X0000465933Y0000186311
X0000461996Y0000186311
X0000454122Y0000178437
X0000465933Y0000166627
X0000465933Y0000209933
X0000454122Y0000205996
X0000450185Y0000217807
X0000446248Y0000190248
X0000442311Y0000202059
X0000469870Y0000198122
X0000458059Y0000194185
X0000473807Y0000186311
X0000461996Y0000182374
X0000450185Y0000178437
X0000469870Y0000154816
X0000458059Y0000150879
X0000442311Y0000178437
X0000446248Y0000170564
X0000450185Y0000166627
X0000442311Y0000166627
X0000450185Y0000158753
X0000446248Y0000162690
X0000446248Y0000154816
X0000442311Y0000158753
X0000442311Y0000209933
X0000454122Y0000182374
X0000454122Y0000217807
X0000458059Y0000190248
X0000465933Y0000194185
X0000454122Y0000162690
X0000454122Y0000166627
X0000454122Y0000158753
X0000454123Y0000170564
X0000473807Y0000166627
X0000442311Y0000154816
X0000469870Y0000217807
X0000458059Y0000213870
X0000450185Y0000198122
X0000446248Y0000209933
X0000473807Y0000205996
X0000461996Y0000202059
X0000465933Y0000190248
X0000454122Y0000186311
X0000442311Y0000182374
X0000469870Y0000178437
X0000446248Y0000178437
X0000450185Y0000170564
X0000442311Y0000170564
X0000446248Y0000166627
X0000458059Y0000166627
X0000450185Y0000162690
X0000442311Y0000162690
X0000461996Y0000158753
X0000446248Y0000158753
X0000450185Y0000154816
X0000442311Y0000186311
X0000446248Y0000186311
X0000465933Y0000154816
X0000458059Y0000158753
X0000450185Y0000182374
X0000446248Y0000182374
X0000458059Y0000178437
X0000450185Y0000139067
X0000469870Y0000143005
X0000465933Y0000143005
X0000461996Y0000143005
X0000458059Y0000143005
X0000454122Y0000146942
X0000450185Y0000146942
X0000461996Y0000146942
X0000458059Y0000146942
X0000454122Y0000131193
X0000449876Y0000131502
X0000457844Y0000135345
X0000454122Y0000135130
X0000445939Y0000135439
X0000446248Y0000139067
X0000465933Y0000135130
X0000461996Y0000135130
X0000458059Y0000139067
X0000454122Y0000139067
X0000473807Y0000131193
X0000469870Y0000131193
X0000469870Y0000139067
X0000465933Y0000139067
X0000442311Y0000146942
X0000442311Y0000143005
X0000473807Y0000143005
X0000461996Y0000139067
X0000450185Y0000135130
X0000446248Y0000146942
X0000440850Y0000116599
X0000446248Y0000143005
X0000450185Y0000143005
X0000469870Y0000146942
X0000473807Y0000146942
X0000473807Y0000139067
X0000473807Y0000135130
X0000490970Y0000138500
X0000454130Y0000122167
X0000461996Y0000131193
X0000457330Y0000122167
X0000465933Y0000131193
X0000490970Y0000133500
X0000460530Y0000122167
X0000450930Y0000122167
X0000469870Y0000135130
X0000457844Y0000131408
X0000454122Y0000143005
X0000442311Y0000139067
X0000465933Y0000146942
X0000444050Y0000116599
X0000537402Y0000054197
X0000533402Y0000054197
X0000529402Y0000054197
X0000525402Y0000054197
X0000521402Y0000054197
X0000517402Y0000054197
X0000513402Y0000054197
X0000509402Y0000054197
X0000505402Y0000054197
X0000501402Y0000054197
X0000497402Y0000054197
X0000493402Y0000054197
X0000489402Y0000054197
X0000485402Y0000054197
X0000481402Y0000054197
X0000477402Y0000054197
X0000473402Y0000054197
X0000469402Y0000054197
X0000465402Y0000054197
X0000461402Y0000054197
X0000457402Y0000054197
X0000453402Y0000054197
X0000449402Y0000054197
X0000445402Y0000054197
X0000441402Y0000054197
X0000533000Y0000099500
X0000533000Y0000095000
X0000549500Y0000069400
X0000572500Y0000060301
X0000568600Y0000076000
X0000572870Y0000067570
X0000629402Y0000054197
X0000625402Y0000054197
X0000621402Y0000054197
X0000617402Y0000054197
X0000613402Y0000054197
X0000609402Y0000054197
X0000605402Y0000054197
X0000601402Y0000054197
X0000597402Y0000054197
X0000593402Y0000054197
X0000589402Y0000054197
X0000585402Y0000054197
X0000581402Y0000054197
X0000577402Y0000054197
X0000573402Y0000054197
X0000569402Y0000054197
X0000565402Y0000054197
X0000561402Y0000054197
X0000557402Y0000054197
X0000553402Y0000054197
X0000549402Y0000054197
X0000545402Y0000054197
X0000541402Y0000054197
X0000594153Y0000220500
X0000601902Y0000200100
X0000589953Y0000236600
X0000619961Y0000227674
X0000619961Y0000224474
X0000548158Y0000228033
X0000566700Y0000227500
X0000559500Y0000228000
X0000577100Y0000227900
X0000553122Y0000227979
X0000625800Y0000215874
X0000633500Y0000205906
X0000597000Y0000199900
X0000619961Y0000221274
X0000619961Y0000230874
X0000566600Y0000212900
X0000591902Y0000200300
X0000606902Y0000200400
X0000576200Y0000342500
X0000581400Y0000282100
X0000581400Y0000272100
X0000581500Y0000302100
X0000581400Y0000262100
X0000633000Y0000267000
X0000591000Y0000261500
X0000590500Y0000301500
X0000545250Y0000256300
X0000555200Y0000371141
X0000555200Y0000374684
X0000555200Y0000378227
X0000555200Y0000367597
X0000552000Y0000378227
X0000552000Y0000374684
X0000552000Y0000371141
X0000552000Y0000367597
X0000555569Y0000388051
X0000550643Y0000400900
X0000568000Y0000356700
X0000540413Y0000433598
X0000544413Y0000433598
X0000548413Y0000433598
X0000552413Y0000433598
X0000556413Y0000433598
X0000560413Y0000433598
X0000564413Y0000433598
X0000568413Y0000433598
X0000572413Y0000433598
X0000576413Y0000433598
X0000580413Y0000433598
X0000584413Y0000433598
X0000588413Y0000433598
X0000592413Y0000433598
X0000596413Y0000433598
X0000600413Y0000433598
X0000604413Y0000433598
X0000608413Y0000433598
X0000612413Y0000433598
X0000616413Y0000433598
X0000620413Y0000433598
X0000624413Y0000433598
X0000628413Y0000433598
X0000632413Y0000433598
X0000636413Y0000433598
X0000640413Y0000433598
X0000644413Y0000433598
X0000648413Y0000433598
X0000652413Y0000433598
X0000656039Y0000431909
X0000656039Y0000427909
X0000656039Y0000423909
X0000656039Y0000419909
X0000656039Y0000415909
X0000656039Y0000411909
X0000656039Y0000407909
X0000656039Y0000403909
X0000656039Y0000399909
X0000656039Y0000395909
X0000656039Y0000391909
X0000656039Y0000387909
X0000656039Y0000383909
X0000656039Y0000379909
X0000656039Y0000375909
X0000656039Y0000371909
X0000656039Y0000367909
X0000656039Y0000363909
X0000656039Y0000359909
X0000656039Y0000355909
X0000656039Y0000351909
X0000656039Y0000347909
X0000656039Y0000343909
X0000656039Y0000339909
X0000656039Y0000335909
X0000656039Y0000331909
X0000656039Y0000327909
X0000656039Y0000323909
X0000656039Y0000319909
X0000656039Y0000315909
X0000656039Y0000311909
X0000656039Y0000181205
X0000656039Y0000177205
X0000656039Y0000173205
X0000656039Y0000169205
X0000656039Y0000165205
X0000656039Y0000161205
X0000656039Y0000157205
X0000656039Y0000153205
X0000656039Y0000235585
X0000656039Y0000141205
X0000656039Y0000137205
X0000656039Y0000133205
X0000656039Y0000129205
X0000656039Y0000125205
X0000656039Y0000121205
X0000656039Y0000117205
X0000656039Y0000113205
X0000656039Y0000109205
X0000656039Y0000149205
X0000656039Y0000145205
X0000656039Y0000105205
X0000656039Y0000101205
X0000656039Y0000097205
X0000656039Y0000093205
X0000656039Y0000089205
X0000656039Y0000085205
X0000656039Y0000081205
X0000656039Y0000077205
X0000656039Y0000073205
X0000656039Y0000069205
X0000656039Y0000065205
X0000656039Y0000061205
X0000656039Y0000057205
X0000653402Y0000054197
X0000649402Y0000054197
T02
X0000012500Y0000106000
X0000012500Y0000101000
X0000012500Y0000091000
X0000013620Y0000148720
X0000028100Y0000148798
X0000037100Y0000148798
X0000023600Y0000148798
X0000032600Y0000148700
X0000019100Y0000148798
X0000012500Y0000096000
X0000017500Y0000091000
X0000012500Y0000219500
X0000012500Y0000214500
X0000012500Y0000204500
X0000012500Y0000162000
X0000013000Y0000157000
X0000012500Y0000209500
X0000011264Y0000152264
X0000017000Y0000204500
X0000035500Y0000327000
X0000028000Y0000327000
X0000013000Y0000318700
X0000013000Y0000273327
X0000028700Y0000274300
X0000012500Y0000261500
X0000028700Y0000262508
X0000024200Y0000262508
X0000034500Y0000309000
X0000039500Y0000309000
X0000033200Y0000262508
X0000019000Y0000262500
X0000015000Y0000279000
X0000009000Y0000286000
X0000009000Y0000279000
X0000033000Y0000314500
X0000018000Y0000314500
X0000011976Y0000323524
X0000024100Y0000310900
X0000016000Y0000297500
X0000037400Y0000282900
X0000011963Y0000266437
X0000029000Y0000291500
X0000028000Y0000296500
X0000028500Y0000302000
X0000016000Y0000302500
X0000016000Y0000307500
X0000019900Y0000283000
X0000097800Y0000391800
X0000099500Y0000370000
X0000114000Y0000352000
X0000124500Y0000352000
X0000104500Y0000377000
X0000137000Y0000364000
X0000092800Y0000396100
X0000096800Y0000396100
X0000096800Y0000402100
X0000092800Y0000402100
X0000092800Y0000408100
X0000096800Y0000408100
X0000092800Y0000414100
X0000096800Y0000414100
X0000060300Y0000395100
X0000064300Y0000395600
X0000060300Y0000401100
X0000064300Y0000401600
X0000060300Y0000407100
X0000064300Y0000407600
X0000060300Y0000413100
X0000064300Y0000413600
X0000085400Y0000394200
X0000080700Y0000394200
X0000076000Y0000394200
X0000071300Y0000394200
X0000076000Y0000404200
X0000076000Y0000399200
X0000071300Y0000399200
X0000071300Y0000404200
X0000071300Y0000409200
X0000076000Y0000409200
X0000080700Y0000409200
X0000080700Y0000404200
X0000080700Y0000399200
X0000085400Y0000399200
X0000085400Y0000404200
X0000085400Y0000409200
X0000103000Y0000351500
X0000119000Y0000352000
X0000055000Y0000355400
X0000083000Y0000352500
X0000095100Y0000351900
X0000130000Y0000349664
X0000083500Y0000360000
X0000091500Y0000359500
X0000080500Y0000420500
X0000140000Y0000401000
X0000135100Y0000412600
X0000086500Y0000364500
X0000090500Y0000364500
X0000094500Y0000364500
X0000094500Y0000369000
X0000094500Y0000373000
X0000094500Y0000376500
X0000086500Y0000384500
X0000090500Y0000384500
X0000094000Y0000384500
X0000094500Y0000380500
X0000082800Y0000384600
X0000082800Y0000364600
X0000135200Y0000408400
X0000070500Y0000382000
X0000066500Y0000382000
X0000062500Y0000382000
X0000062500Y0000378000
X0000062500Y0000373000
X0000066000Y0000365000
X0000069500Y0000365000
X0000073000Y0000365000
X0000062500Y0000369000
X0000062500Y0000365000
X0000135500Y0000390500
X0000121169Y0000396892
X0000083000Y0000417000
X0000132000Y0000375500
X0000063500Y0000359600
X0000120000Y0000371500
X0000120000Y0000368000
X0000115500Y0000389000
X0000117000Y0000397000
X0000127000Y0000397061
X0000129000Y0000370500
X0000135500Y0000383000
X0000135500Y0000396000
X0000118500Y0000379000
X0000132000Y0000379000
X0000129000Y0000365000
X0000120000Y0000364500
X0000110000Y0000364000
X0000106500Y0000364000
X0000103000Y0000364000
X0000099000Y0000350000
X0000066000Y0000419000
X0000102500Y0000420000
X0000094000Y0000420000
X0000140100Y0000395600
X0000140123Y0000391604
X0000064700Y0000251700
X0000063600Y0000291500
X0000078000Y0000330500
X0000071000Y0000330500
X0000087500Y0000295500
X0000095000Y0000291500
X0000079500Y0000308500
X0000088500Y0000303000
X0000094500Y0000299000
X0000052800Y0000272000
X0000072000Y0000346300
X0000113000Y0000344500
X0000095000Y0000344500
X0000115253Y0000306247
X0000095000Y0000321500
X0000094500Y0000312500
X0000117500Y0000290000
X0000102500Y0000302000
X0000055000Y0000336000
X0000102500Y0000290000
X0000112500Y0000290000
X0000083000Y0000344500
X0000079500Y0000348500
X0000082951Y0000327940
X0000079000Y0000315500
X0000078635Y0000324492
X0000126000Y0000318000
X0000129500Y0000328000
X0000107500Y0000302000
X0000112500Y0000302000
X0000129000Y0000321500
X0000105410Y0000318500
X0000104019Y0000347425
X0000097500Y0000341000
X0000101500Y0000341000
X0000062000Y0000323500
X0000082500Y0000339000
X0000079500Y0000341790
X0000066000Y0000318500
X0000066000Y0000323500
X0000135000Y0000312000
X0000043000Y0000255500
X0000044500Y0000309000
X0000055200Y0000253500
X0000048500Y0000252500
X0000048232Y0000264530
X0000052500Y0000278000
X0000040500Y0000262000
X0000043000Y0000314500
X0000086900Y0000267200
X0000064248Y0000258000
X0000083200Y0000260300
X0000069500Y0000257800
X0000095900Y0000278900
X0000140100Y0000306900
X0000078000Y0000291500
X0000054590Y0000266870
X0000099000Y0000260025
X0000098500Y0000256661
X0000127500Y0000290500
X0000125095Y0000306095
X0000095593Y0000333347
X0000057500Y0000289000
X0000072000Y0000335000
X0000104500Y0000305500
X0000123500Y0000347500
X0000048500Y0000271500
X0000061489Y0000332329
X0000080148Y0000253648
X0000098800Y0000272400
X0000098700Y0000268300
X0000087200Y0000258300
X0000072400Y0000264600
X0000062000Y0000307000
X0000064500Y0000296750
X0000062000Y0000199500
X0000054500Y0000171000
X0000057500Y0000226500
X0000049600Y0000213455
X0000048957Y0000153619
X0000060600Y0000157000
X0000083500Y0000173000
X0000069023Y0000198524
X0000069000Y0000193000
X0000069000Y0000187500
X0000090500Y0000193500
X0000094500Y0000197000
X0000090500Y0000188500
X0000063000Y0000215000
X0000098500Y0000218500
X0000063000Y0000210500
X0000099000Y0000201500
X0000063000Y0000206000
X0000099000Y0000197500
X0000092000Y0000173000
X0000098500Y0000165500
X0000098500Y0000159000
X0000099000Y0000188500
X0000099000Y0000206500
X0000097500Y0000214000
X0000053000Y0000200500
X0000045500Y0000182500
X0000046000Y0000219500
X0000053500Y0000183500
X0000053200Y0000240187
X0000048000Y0000200500
X0000054000Y0000213500
X0000045000Y0000213000
X0000096500Y0000235500
X0000054130Y0000152500
X0000094500Y0000163000
X0000097500Y0000172000
X0000083500Y0000188500
X0000083500Y0000193000
X0000083500Y0000178000
X0000095500Y0000192000
X0000099000Y0000175500
X0000095200Y0000151000
X0000093900Y0000155200
X0000095700Y0000227500
X0000071400Y0000232900
X0000084500Y0000218000
X0000067400Y0000227100
X0000085700Y0000236500
X0000067700Y0000240200
X0000051452Y0000219900
X0000058000Y0000213500
X0000064445Y0000168945
X0000088400Y0000154900
X0000051400Y0000161600
X0000060500Y0000152000
X0000096000Y0000241000
X0000068000Y0000235500
X0000042000Y0000236800
X0000045500Y0000161000
X0000060600Y0000161200
X0000051772Y0000245074
X0000067500Y0000222900
X0000057500Y0000218500
X0000051772Y0000187987
X0000053900Y0000157000
X0000085750Y0000202750
X0000071500Y0000247800
X0000071400Y0000221700
X0000074593Y0000202207
X0000093032Y0000246477
X0000088250Y0000177250
X0000091000Y0000181500
X0000229582Y0000048918
X0000063500Y0000084500
X0000064500Y0000129500
X0000064400Y0000070000
X0000056500Y0000113000
X0000075500Y0000062000
X0000057500Y0000101500
X0000074000Y0000100500
X0000079000Y0000100500
X0000084000Y0000100500
X0000071500Y0000077000
X0000126000Y0000072000
X0000084200Y0000075000
X0000074000Y0000130000
X0000078500Y0000082250
X0000069500Y0000130000
X0000076321Y0000078300
X0000073500Y0000119000
X0000068000Y0000119000
X0000067500Y0000114500
X0000091500Y0000140000
X0000096500Y0000140000
X0000093500Y0000130000
X0000087000Y0000125500
X0000093500Y0000125000
X0000044500Y0000073500
X0000045500Y0000104390
X0000050500Y0000060228
X0000053740Y0000126000
X0000051500Y0000083500
X0000047500Y0000140500
X0000067000Y0000109000
X0000073500Y0000112500
X0000090500Y0000105000
X0000062500Y0000100500
X0000093500Y0000110500
X0000048390Y0000128312
X0000055500Y0000059000
X0000088500Y0000149000
X0000075000Y0000141700
X0000041500Y0000127500
X0000087000Y0000120000
X0000046500Y0000133000
X0000087000Y0000130000
X0000041409Y0000132591
X0000089000Y0000110500
X0000041600Y0000148798
X0000062500Y0000117000
X0000059000Y0000096500
X0000050500Y0000104800
X0000082100Y0000079300
X0000076400Y0000087200
X0000125000Y0000076500
X0000111330Y0000059810
X0000086000Y0000063100
X0000060100Y0000073000
X0000059600Y0000060200
X0000095500Y0000145500
X0000090500Y0000144500
X0000055922Y0000140543
X0000057000Y0000083500
X0000094500Y0000105000
X0000086600Y0000141300
X0000045500Y0000126000
X0000103800Y0000076240
X0000066400Y0000077400
X0000083300Y0000087100
X0000066000Y0000091100
X0000069500Y0000100000
X0000051772Y0000130500
X0000047600Y0000068900
X0000061400Y0000104900
X0000051772Y0000073600
X0000047000Y0000100000
X0000067700Y0000065000
X0000088900Y0000067000
X0000119500Y0000057694
X0000092250Y0000097750
X0000096500Y0000098000
X0000207800Y0000083010
X0000204770Y0000067780
X0000228500Y0000079000
X0000228500Y0000075500
X0000160500Y0000071500
X0000160500Y0000075500
X0000153270Y0000058400
X0000151200Y0000075191
X0000173170Y0000070840
X0000223500Y0000058250
X0000213500Y0000054000
X0000231000Y0000071500
X0000231000Y0000068000
X0000220000Y0000069000
X0000215000Y0000069000
X0000192160Y0000077840
X0000150860Y0000067400
X0000208160Y0000073990
X0000188900Y0000054960
X0000201700Y0000327900
X0000153500Y0000310500
X0000156000Y0000316500
X0000156000Y0000320500
X0000156600Y0000295000
X0000166700Y0000343800
X0000219000Y0000348800
X0000219200Y0000338800
X0000141916Y0000333916
X0000140700Y0000320000
X0000149500Y0000311034
X0000156800Y0000301100
X0000173800Y0000324100
X0000176500Y0000290000
X0000178000Y0000309500
X0000179500Y0000294600
X0000215000Y0000343800
X0000205000Y0000348800
X0000230000Y0000347500
X0000225500Y0000347500
X0000146000Y0000334000
X0000195900Y0000332500
X0000182600Y0000289500
X0000156000Y0000329000
X0000156000Y0000325000
X0000238000Y0000345000
X0000169850Y0000298950
X0000166150Y0000304050
X0000141000Y0000298500
X0000145000Y0000296500
X0000151000Y0000324200
X0000189000Y0000326000
X0000189500Y0000319000
X0000190000Y0000305500
X0000190000Y0000301500
X0000165000Y0000294000
X0000168500Y0000294000
X0000142130Y0000325630
X0000166700Y0000338800
X0000222500Y0000324500
X0000226500Y0000334000
X0000225000Y0000396000
X0000145000Y0000359000
X0000151500Y0000358000
X0000159100Y0000354600
X0000205000Y0000353800
X0000177000Y0000398000
X0000175000Y0000394500
X0000151700Y0000411300
X0000157900Y0000387400
X0000158500Y0000405200
X0000143500Y0000418000
X0000220000Y0000396000
X0000216500Y0000396000
X0000215500Y0000392500
X0000219000Y0000392500
X0000145000Y0000378000
X0000148500Y0000380000
X0000160550Y0000413400
X0000160582Y0000410000
X0000163600Y0000378600
X0000159100Y0000382600
X0000141000Y0000379500
X0000159100Y0000350400
X0000142000Y0000350000
X0000140900Y0000355400
X0000176000Y0000416000
X0000226000Y0000378500
X0000221500Y0000378500
X0000148000Y0000370000
X0000151500Y0000370000
X0000191500Y0000413000
X0000174600Y0000406100
X0000174600Y0000410600
X0000175100Y0000387100
X0000174600Y0000401600
X0000175100Y0000382600
X0000178600Y0000374600
X0000178600Y0000378600
X0000229500Y0000415000
X0000228500Y0000382500
X0000217600Y0000415100
X0000225600Y0000415100
X0000221500Y0000415000
X0000218000Y0000381100
X0000323000Y0000401500
X0000320000Y0000398500
X0000336300Y0000419200
X0000336300Y0000415200
X0000336300Y0000423200
X0000339300Y0000387700
X0000339300Y0000384000
X0000339200Y0000380300
X0000336500Y0000361300
X0000325000Y0000363000
X0000332500Y0000361300
X0000338500Y0000376000
X0000331500Y0000376000
X0000326000Y0000374000
X0000325300Y0000391700
X0000325300Y0000396200
X0000324800Y0000410700
X0000321300Y0000416700
X0000324800Y0000415200
X0000321300Y0000423600
X0000325300Y0000387200
X0000337000Y0000344000
X0000337500Y0000265000
X0000330500Y0000265000
X0000323500Y0000263000
X0000332000Y0000301500
X0000324000Y0000301000
X0000312000Y0000264500
X0000293700Y0000317300
X0000301000Y0000317000
X0000312500Y0000307500
X0000297000Y0000310500
X0000312000Y0000256500
X0000338500Y0000259000
X0000255400Y0000290100
X0000312000Y0000269000
X0000310600Y0000326000
X0000339500Y0000282000
X0000333500Y0000258900
X0000249000Y0000290300
X0000310500Y0000321000
X0000324500Y0000295500
X0000321000Y0000295500
X0000317500Y0000295500
X0000259000Y0000344500
X0000255000Y0000344500
X0000251000Y0000344500
X0000247000Y0000344500
X0000288500Y0000317000
X0000330500Y0000291500
X0000314500Y0000276500
X0000312000Y0000295500
X0000299500Y0000295500
X0000292000Y0000294720
X0000288000Y0000293000
X0000301000Y0000312000
X0000311600Y0000252400
X0000321899Y0000343000
X0000328500Y0000258900
X0000338000Y0000315000
X0000328000Y0000306500
X0000332500Y0000306500
X0000306500Y0000169500
X0000338500Y0000213500
X0000312500Y0000160500
X0000303500Y0000164000
X0000307500Y0000160500
X0000311900Y0000229900
X0000320500Y0000170000
X0000312500Y0000225400
X0000332550Y0000213550
X0000335153Y0000217875
X0000327923Y0000221577
X0000324000Y0000220750
X0000309000Y0000164500
X0000311900Y0000243400
X0000297772Y0000188694
X0000300995Y0000187611
X0000298500Y0000184500
X0000282200Y0000179121
X0000271000Y0000184500
X0000311000Y0000193500
X0000241900Y0000238800
X0000280500Y0000224300
X0000275260Y0000223000
X0000308967Y0000204000
X0000241441Y0000215000
X0000269000Y0000215000
X0000254000Y0000213500
X0000259000Y0000223000
X0000312000Y0000234400
X0000312000Y0000217000
X0000324000Y0000227500
X0000298284Y0000175184
X0000338000Y0000102500
X0000296400Y0000070200
X0000336000Y0000061060
X0000259500Y0000054700
X0000272330Y0000054871
X0000259500Y0000070100
X0000303500Y0000069400
X0000370500Y0000084000
X0000420500Y0000082000
X0000415000Y0000123500
X0000418500Y0000117000
X0000422000Y0000123500
X0000429000Y0000123500
X0000382286Y0000086214
X0000362000Y0000128000
X0000362000Y0000123500
X0000417500Y0000075000
X0000369172Y0000102828
X0000369310Y0000109500
X0000355000Y0000141500
X0000352500Y0000141500
X0000350000Y0000141500
X0000347500Y0000141500
X0000425000Y0000087700
X0000382000Y0000142000
X0000379000Y0000141000
X0000374000Y0000141000
X0000376500Y0000141000
X0000344000Y0000103000
X0000340500Y0000063500
X0000423000Y0000072950
X0000399500Y0000120000
X0000407000Y0000120000
X0000413500Y0000088500
X0000356000Y0000130500
X0000353500Y0000130500
X0000351000Y0000130500
X0000354000Y0000128000
X0000371800Y0000132000
X0000374300Y0000132000
X0000371800Y0000129000
X0000374300Y0000129000
X0000367000Y0000126000
X0000384000Y0000109500
X0000384000Y0000102980
X0000376838Y0000100230
X0000429400Y0000107500
X0000427800Y0000100300
X0000422000Y0000077500
X0000434500Y0000077000
X0000431000Y0000116500
X0000433500Y0000100500
X0000423000Y0000100500
X0000354000Y0000082500
X0000345500Y0000087000
X0000340500Y0000087000
X0000354500Y0000060920
X0000349500Y0000061000
X0000374600Y0000178200
X0000390000Y0000232500
X0000383000Y0000232500
X0000375000Y0000210000
X0000380000Y0000210000
X0000414900Y0000229800
X0000416100Y0000235400
X0000423000Y0000235400
X0000394000Y0000223500
X0000420500Y0000229500
X0000425400Y0000229600
X0000365500Y0000246500
X0000373649Y0000185735
X0000415000Y0000246800
X0000420900Y0000246800
X0000409300Y0000246800
X0000403700Y0000246800
X0000380100Y0000246800
X0000386000Y0000246800
X0000391900Y0000246800
X0000397800Y0000246800
X0000384091Y0000200091
X0000351000Y0000233243
X0000344000Y0000212000
X0000349128Y0000186628
X0000379500Y0000237500
X0000407500Y0000225000
X0000373500Y0000247000
X0000377500Y0000223500
X0000377500Y0000226500
X0000377500Y0000221000
X0000377500Y0000218500
X0000355500Y0000223000
X0000355500Y0000225500
X0000355500Y0000220500
X0000355500Y0000218000
X0000367900Y0000154228
X0000371400Y0000154300
X0000378400Y0000154300
X0000374900Y0000154228
X0000360500Y0000154500
X0000350085Y0000154300
X0000353482Y0000154157
X0000357000Y0000154200
X0000344500Y0000181500
X0000367400Y0000174400
X0000436500Y0000233000
X0000436500Y0000237500
X0000346500Y0000174000
X0000351000Y0000237000
X0000380000Y0000204500
X0000347300Y0000179000
X0000379800Y0000177100
X0000364700Y0000169400
X0000367600Y0000169300
X0000355100Y0000169400
X0000357600Y0000169400
X0000352600Y0000169400
X0000350100Y0000169400
X0000363600Y0000176600
X0000372500Y0000232000
X0000364500Y0000213000
X0000367000Y0000213000
X0000399000Y0000225000
X0000399000Y0000221407
X0000372060Y0000213000
X0000369560Y0000213000
X0000367000Y0000241243
X0000367000Y0000232000
X0000354975Y0000247900
X0000360500Y0000243000
X0000355000Y0000242500
X0000341500Y0000233500
X0000350500Y0000229500
X0000340953Y0000237000
X0000351200Y0000196600
X0000344500Y0000265000
X0000408000Y0000327000
X0000365500Y0000279500
X0000358000Y0000261500
X0000429000Y0000274000
X0000365000Y0000268000
X0000376500Y0000269000
X0000351000Y0000308000
X0000346000Y0000306500
X0000428500Y0000346000
X0000408500Y0000311000
X0000434000Y0000328000
X0000392500Y0000323900
X0000434500Y0000302000
X0000407500Y0000300500
X0000392500Y0000329100
X0000439000Y0000302000
X0000413000Y0000300500
X0000440000Y0000332500
X0000410000Y0000338000
X0000390000Y0000338500
X0000429442Y0000310075
X0000408500Y0000321998
X0000435000Y0000250500
X0000435143Y0000306643
X0000370000Y0000332500
X0000433000Y0000314320
X0000383000Y0000323500
X0000408500Y0000316500
X0000349000Y0000295500
X0000398000Y0000336500
X0000370000Y0000337000
X0000355000Y0000337000
X0000417500Y0000337000
X0000371000Y0000326000
X0000341400Y0000323500
X0000341000Y0000304000
X0000357680Y0000271780
X0000348500Y0000260000
X0000352500Y0000260000
X0000386000Y0000259250
X0000375800Y0000255200
X0000420900Y0000259000
X0000424900Y0000292900
X0000423900Y0000278500
X0000424900Y0000284300
X0000439500Y0000250000
X0000396981Y0000304482
X0000394800Y0000281300
X0000374500Y0000276000
X0000370000Y0000276000
X0000382200Y0000281000
X0000378000Y0000281000
X0000389400Y0000281100
X0000375500Y0000309200
X0000365500Y0000305900
X0000361400Y0000309900
X0000361400Y0000305800
X0000361400Y0000301500
X0000433050Y0000291400
X0000438150Y0000283800
X0000435500Y0000274500
X0000434600Y0000278300
X0000440000Y0000278500
X0000400000Y0000265500
X0000349000Y0000303000
X0000355500Y0000306500
X0000369500Y0000267500
X0000383000Y0000341500
X0000403700Y0000259300
X0000397800Y0000259300
X0000397300Y0000320700
X0000407500Y0000305000
X0000439500Y0000266500
X0000362100Y0000291000
X0000365800Y0000286100
X0000365800Y0000291100
X0000362300Y0000286100
X0000361500Y0000296100
X0000409300Y0000286300
X0000409100Y0000281300
X0000409200Y0000291700
X0000378000Y0000273500
X0000343500Y0000258900
X0000397500Y0000312900
X0000399800Y0000278400
X0000383000Y0000293200
X0000378000Y0000293200
X0000370300Y0000291100
X0000374800Y0000291100
X0000393300Y0000312500
X0000388650Y0000292650
X0000402500Y0000308000
X0000402000Y0000303000
X0000356000Y0000302300
X0000357000Y0000295500
X0000374500Y0000418500
X0000430000Y0000386500
X0000395000Y0000382000
X0000369000Y0000413500
X0000431000Y0000406500
X0000431000Y0000411500
X0000438500Y0000364500
X0000420500Y0000366000
X0000422500Y0000354500
X0000395000Y0000360000
X0000395000Y0000370000
X0000411840Y0000353620
X0000433382Y0000360466
X0000433500Y0000366500
X0000409000Y0000371339
X0000379500Y0000375800
X0000420500Y0000381000
X0000419000Y0000373500
X0000389500Y0000370000
X0000413500Y0000373500
X0000379500Y0000381000
X0000406610Y0000353410
X0000433000Y0000353500
X0000430000Y0000381000
X0000383900Y0000384600
X0000438400Y0000382400
X0000423500Y0000415500
X0000379500Y0000417500
X0000366000Y0000350850
X0000425000Y0000381000
X0000348863Y0000410500
X0000347000Y0000391200
X0000348279Y0000405678
X0000347600Y0000398800
X0000343700Y0000409900
X0000359800Y0000397700
X0000347700Y0000381600
X0000340500Y0000391600
X0000346000Y0000416000
X0000349500Y0000415000
X0000350000Y0000419500
X0000353000Y0000416500
X0000340800Y0000415200
X0000360700Y0000406200
X0000344500Y0000361300
X0000340500Y0000361300
X0000348418Y0000361300
X0000364500Y0000413500
X0000386500Y0000365000
X0000381000Y0000365000
X0000419150Y0000403950
X0000409650Y0000394450
X0000412350Y0000397150
X0000416450Y0000397150
X0000416450Y0000401250
X0000412350Y0000401250
X0000409650Y0000403950
X0000419150Y0000394450
X0000431000Y0000416000
X0000417500Y0000352000
X0000398000Y0000352000
X0000383900Y0000372600
X0000410000Y0000358543
X0000384300Y0000368700
X0000342000Y0000376000
X0000360000Y0000402400
X0000363100Y0000422800
X0000360311Y0000409880
X0000363100Y0000418300
X0000530000Y0000406500
X0000467000Y0000355500
X0000470500Y0000391000
X0000527500Y0000389100
X0000527500Y0000393100
X0000527500Y0000397100
X0000532100Y0000399000
X0000450000Y0000411500
X0000450000Y0000416500
X0000522100Y0000416500
X0000453500Y0000381500
X0000450500Y0000368500
X0000538558Y0000413779
X0000514000Y0000374000
X0000517500Y0000374000
X0000518000Y0000382500
X0000539000Y0000360000
X0000539300Y0000365100
X0000539000Y0000370000
X0000503500Y0000394500
X0000507500Y0000394500
X0000538558Y0000427558
X0000450000Y0000407000
X0000446000Y0000374500
X0000523700Y0000377700
X0000528200Y0000377700
X0000523700Y0000384100
X0000532200Y0000377700
X0000538500Y0000407875
X0000504500Y0000376000
X0000505000Y0000379500
X0000454000Y0000397000
X0000454000Y0000393500
X0000471400Y0000363300
X0000525176Y0000411925
X0000483100Y0000272800
X0000534500Y0000253600
X0000447000Y0000321998
X0000451000Y0000306500
X0000504500Y0000340500
X0000509000Y0000340500
X0000461500Y0000311000
X0000461500Y0000268409
X0000468500Y0000270000
X0000468500Y0000264500
X0000453000Y0000250000
X0000448500Y0000311500
X0000448500Y0000250000
X0000454000Y0000312500
X0000488500Y0000346000
X0000483501Y0000346000
X0000456500Y0000305500
X0000526000Y0000295500
X0000446000Y0000294000
X0000447000Y0000283000
X0000457500Y0000250000
X0000495000Y0000346000
X0000519000Y0000307500
X0000537500Y0000304000
X0000464500Y0000298500
X0000461000Y0000302500
X0000450900Y0000330900
X0000501000Y0000263500
X0000531000Y0000285500
X0000460800Y0000294200
X0000523900Y0000257100
X0000524300Y0000261700
X0000497000Y0000341000
X0000481000Y0000341000
X0000478500Y0000346000
X0000523600Y0000281100
X0000445600Y0000278300
X0000506100Y0000280600
X0000532500Y0000272500
X0000512650Y0000268150
X0000508950Y0000273250
X0000459000Y0000326000
X0000447200Y0000347500
X0000459500Y0000322000
X0000527600Y0000318900
X0000532900Y0000318900
X0000538600Y0000318900
X0000527100Y0000345600
X0000527100Y0000340600
X0000532400Y0000345600
X0000538100Y0000345600
X0000532400Y0000340600
X0000538100Y0000340600
X0000444000Y0000263000
X0000460000Y0000289500
X0000460000Y0000284500
X0000511900Y0000276200
X0000462000Y0000250000
X0000444000Y0000250000
X0000477500Y0000259000
X0000471000Y0000259200
X0000491800Y0000277700
X0000492500Y0000272200
X0000471000Y0000347000
X0000530350Y0000257480
X0000512200Y0000258700
X0000512300Y0000254400
X0000512100Y0000262500
X0000459500Y0000262000
X0000457000Y0000258500
X0000539500Y0000292000
X0000497000Y0000154000
X0000482000Y0000212500
X0000473807Y0000150879
X0000461996Y0000162690
X0000465933Y0000162690
X0000473807Y0000154816
X0000491000Y0000154000
X0000485000Y0000154000
X0000503000Y0000155000
X0000461000Y0000230000
X0000449000Y0000227500
X0000443500Y0000231500
X0000449000Y0000232500
X0000443500Y0000236500
X0000457500Y0000223500
X0000457500Y0000227500
X0000497500Y0000226000
X0000492500Y0000226000
X0000509000Y0000215500
X0000513500Y0000215500
X0000511500Y0000206500
X0000513000Y0000210500
X0000457500Y0000237400
X0000461000Y0000234500
X0000515500Y0000201000
X0000477500Y0000170500
X0000484000Y0000185500
X0000481500Y0000193000
X0000485033Y0000174934
X0000490500Y0000216750
X0000485000Y0000202739
X0000496500Y0000197500
X0000477000Y0000239000
X0000471000Y0000239000
X0000497000Y0000175000
X0000496000Y0000163000
X0000522000Y0000247000
X0000525400Y0000247000
X0000514500Y0000157000
X0000514500Y0000154000
X0000514500Y0000151000
X0000539770Y0000172400
X0000539770Y0000169900
X0000539770Y0000174900
X0000483871Y0000198241
X0000480288Y0000203788
X0000479246Y0000178464
X0000484000Y0000166000
X0000481000Y0000172500
X0000448500Y0000237500
X0000537500Y0000232000
X0000534000Y0000231500
X0000502200Y0000240700
X0000492300Y0000240800
X0000497200Y0000240600
X0000497100Y0000244700
X0000528710Y0000227500
X0000462000Y0000224500
X0000517000Y0000212500
X0000496000Y0000179258
X0000538500Y0000189500
X0000534000Y0000160500
X0000496500Y0000192500
X0000496000Y0000205500
X0000534600Y0000152000
X0000496000Y0000167500
X0000478000Y0000198000
X0000512100Y0000244700
X0000512100Y0000240700
X0000529800Y0000223000
X0000533200Y0000220000
X0000536900Y0000201500
X0000507100Y0000240700
X0000481500Y0000182016
X0000444000Y0000226000
X0000512100Y0000249500
X0000507000Y0000188500
X0000507000Y0000192500
X0000498060Y0000185500
X0000501500Y0000192500
X0000497500Y0000214000
X0000479500Y0000092500
X0000491500Y0000148500
X0000503500Y0000149000
X0000497500Y0000148500
X0000476800Y0000120700
X0000482800Y0000110300
X0000483000Y0000133000
X0000481600Y0000125800
X0000466500Y0000110400
X0000471200Y0000115700
X0000520000Y0000087000
X0000458500Y0000086500
X0000519500Y0000075500
X0000496000Y0000085000
X0000519500Y0000081500
X0000493700Y0000079161
X0000470500Y0000082500
X0000475500Y0000082500
X0000536500Y0000079000
X0000536500Y0000084500
X0000460000Y0000076000
X0000503950Y0000133500
X0000465500Y0000078500
X0000463500Y0000092000
X0000524900Y0000099000
X0000533000Y0000082000
X0000526500Y0000067500
X0000503900Y0000128690
X0000503860Y0000124150
X0000462500Y0000117000
X0000448500Y0000100500
X0000514500Y0000144000
X0000514500Y0000148000
X0000529500Y0000060500
X0000521500Y0000060000
X0000463500Y0000086500
X0000533000Y0000087000
X0000481000Y0000070700
X0000454600Y0000108500
X0000533500Y0000124500
X0000534500Y0000130000
X0000534500Y0000136500
X0000450000Y0000108200
X0000537000Y0000069000
X0000493300Y0000121500
X0000489400Y0000126300
X0000479867Y0000138867
X0000503950Y0000143000
X0000534600Y0000148300
X0000448430Y0000089540
X0000444200Y0000100500
X0000441400Y0000078100
X0000508000Y0000110500
X0000522500Y0000114500
X0000513200Y0000066000
X0000508000Y0000115500
X0000508000Y0000105500
X0000482000Y0000083500
X0000478000Y0000078000
X0000508500Y0000064500
X0000504000Y0000064500
X0000503005Y0000099494
X0000541000Y0000096000
X0000576500Y0000098000
X0000580000Y0000104800
X0000544500Y0000079500
X0000592000Y0000146000
X0000622000Y0000146500
X0000622000Y0000141500
X0000592000Y0000141000
X0000633500Y0000096500
X0000633500Y0000102000
X0000633500Y0000108000
X0000600850Y0000112350
X0000599500Y0000116500
X0000622000Y0000127063
X0000637900Y0000116900
X0000592000Y0000127063
X0000588000Y0000096500
X0000553000Y0000108500
X0000551500Y0000059597
X0000549400Y0000081600
X0000544300Y0000087100
X0000549000Y0000078223
X0000549000Y0000063500
X0000562533Y0000102001
X0000565933Y0000102000
X0000592000Y0000136000
X0000622000Y0000136000
X0000599000Y0000092500
X0000564350Y0000065350
X0000563341Y0000062102
X0000559941Y0000062120
X0000585900Y0000079600
X0000580643Y0000060900
X0000580500Y0000065800
X0000543957Y0000060543
X0000559000Y0000088800
X0000560650Y0000070450
X0000560200Y0000081500
X0000559000Y0000085000
X0000562500Y0000074600
X0000586500Y0000112500
X0000586500Y0000107000
X0000576000Y0000246500
X0000587000Y0000184000
X0000595500Y0000239000
X0000558000Y0000161500
X0000540600Y0000234600
X0000592000Y0000157063
X0000622000Y0000157000
X0000592000Y0000168000
X0000622035Y0000167063
X0000592000Y0000178000
X0000622000Y0000175500
X0000622000Y0000151600
X0000622000Y0000162000
X0000622000Y0000181500
X0000592000Y0000151500
X0000592000Y0000163000
X0000592000Y0000173000
X0000601953Y0000218853
X0000602500Y0000183000
X0000594003Y0000187000
X0000610500Y0000190500
X0000618650Y0000249300
X0000614100Y0000236400
X0000585000Y0000226500
X0000558900Y0000202500
X0000554600Y0000202400
X0000569943Y0000223300
X0000542270Y0000172400
X0000542270Y0000169900
X0000543520Y0000174970
X0000565400Y0000244700
X0000548300Y0000222600
X0000566950Y0000220000
X0000578900Y0000236600
X0000560000Y0000240000
X0000576500Y0000219700
X0000571000Y0000217900
X0000541000Y0000216400
X0000545800Y0000216500
X0000546500Y0000240500
X0000628500Y0000189500
X0000627500Y0000205374
X0000590650Y0000245680
X0000587500Y0000190000
X0000606902Y0000186000
X0000596450Y0000210350
X0000601550Y0000208450
X0000597703Y0000187000
X0000626989Y0000237989
X0000616500Y0000194874
X0000575072Y0000165500
X0000542500Y0000189500
X0000576459Y0000161971
X0000544000Y0000159000
X0000583000Y0000192000
X0000580500Y0000194500
X0000610500Y0000227000
X0000614100Y0000224100
X0000633500Y0000196874
X0000543500Y0000205000
X0000540900Y0000201500
X0000553800Y0000240200
X0000564700Y0000204400
X0000568700Y0000204300
X0000573200Y0000204300
X0000586500Y0000230000
X0000636000Y0000216142
X0000566000Y0000347000
X0000556700Y0000320300
X0000561700Y0000320300
X0000562000Y0000331600
X0000562500Y0000326100
X0000562500Y0000336100
X0000560000Y0000342100
X0000633000Y0000286500
X0000591000Y0000278500
X0000591000Y0000291500
X0000591000Y0000271500
X0000583000Y0000297000
X0000541000Y0000281500
X0000554400Y0000267500
X0000562000Y0000254870
X0000542000Y0000296450
X0000633500Y0000301500
X0000581500Y0000267000
X0000551700Y0000256300
X0000549000Y0000267500
X0000541346Y0000303507
X0000581400Y0000292250
X0000609500Y0000254500
X0000604000Y0000254500
X0000571800Y0000396500
X0000560000Y0000401000
X0000614500Y0000403500
X0000609424Y0000413779
X0000597613Y0000413779
X0000590748Y0000418725
X0000597613Y0000427558
X0000609424Y0000427558
X0000602559Y0000417500
X0000614370Y0000417500
X0000597500Y0000421900
X0000584000Y0000421900
X0000614500Y0000398000
X0000604000Y0000398000
X0000555000Y0000402000
X0000548500Y0000411000
X0000572500Y0000413500
X0000562180Y0000413779
X0000567500Y0000403000
X0000568326Y0000371200
X0000568600Y0000380700
X0000568600Y0000376000
X0000567500Y0000386500
X0000540600Y0000386300
X0000576900Y0000403100
X0000564400Y0000396700
X0000580300Y0000390700
X0000543000Y0000360000
X0000543300Y0000365100
X0000543000Y0000370000
X0000568100Y0000361700
X0000568100Y0000366400
X0000591000Y0000404000
X0000602500Y0000404000
X0000573991Y0000427558
X0000550369Y0000427558
X0000562180Y0000427558
X0000580100Y0000366700
X0000580300Y0000385700
X0000580300Y0000356700
X0000543000Y0000396700
X0000563700Y0000352400
X0000580200Y0000361700
X0000576300Y0000371200
X0000580300Y0000375700
X0000580300Y0000380700
X0000560200Y0000386500
X0000564500Y0000379000
X0000548557Y0000387700
X0000548829Y0000416329
X0000555315Y0000417500
X0000567126Y0000417500
X0000578937Y0000417500
X0000563800Y0000390700
X0000647000Y0000108000
X0000647000Y0000113500
T03
X0000029528Y0000046461
X0000036352Y0000043635
X0000039178Y0000036811
X0000036352Y0000029987
X0000029528Y0000027161
X0000022704Y0000029987
X0000019878Y0000036811
X0000022704Y0000043635
X0000029528Y0000382681
X0000036352Y0000379855
X0000039178Y0000373031
X0000036352Y0000366207
X0000029528Y0000363381
X0000022704Y0000366207
X0000019878Y0000373031
X0000022704Y0000379855
X0000640039Y0000075004
X0000640039Y0000055704
X0000633215Y0000058530
X0000630389Y0000065354
X0000633215Y0000072178
X0000640039Y0000427485
X0000640039Y0000408185
X0000633215Y0000411011
X0000630389Y0000417835
X0000633215Y0000424659
X0000646863Y0000424659
X0000649689Y0000417835
X0000646863Y0000411011
X0000646863Y0000072178
X0000649689Y0000065354
X0000646863Y0000058530
T04
X0000024606Y0000343150
X0000028150Y0000343150
X0000031694Y0000343150
X0000035238Y0000343150
X0000038782Y0000343150
X0000037010Y0000340080
X0000033466Y0000340080
X0000029922Y0000340080
X0000026378Y0000340080
X0000022834Y0000340080
X0000042326Y0000343150
X0000045870Y0000343150
X0000044098Y0000340080
X0000040554Y0000340080
T05
X0000640952Y0000201181
X0000640952Y0000220867
T06
X0000016039Y0000128346
X0000016039Y0000071260
X0000016039Y0000242520
X0000016039Y0000185433
T07
X0000006039Y0000138346
X0000026039Y0000138346
X0000006039Y0000118346
X0000026039Y0000118346
X0000006039Y0000081260
X0000026039Y0000081260
X0000006039Y0000061260
X0000026039Y0000061260
X0000006039Y0000232520
X0000026039Y0000232520
X0000006039Y0000195433
X0000026039Y0000195433
X0000006039Y0000175433
X0000026039Y0000175433
X0000006039Y0000252520
X0000026039Y0000252520
T08
X0000605315Y0000334449
X0000588779Y0000334449
X0000605315Y0000367519
X0000605315Y0000350984
X0000588779Y0000367519
X0000588779Y0000350984
T09
X0000126067Y0000264043
X0000126067Y0000184043
X0000126067Y0000104043
X0000286067Y0000264043
X0000286067Y0000104043
X0000277867Y0000093443
X0000265967Y0000093443
X0000253967Y0000093443
T10
X0000255906Y0000412008
X0000255906Y0000309646
X0000494094Y0000412008
X0000494094Y0000309646
T12
X0000143567Y0000106043
X0000146067Y0000268043
X0000268567Y0000255943
X0000268567Y0000112143
T13
X0000634055Y0000334449
X0000634055Y0000367519
T14
X0000029528Y0000036811
X0000029528Y0000373031
X0000640039Y0000065354
X0000640039Y0000417835
M30
